(kicad_pcb
	(version 20260206)
	(generator "pcbnew")
	(generator_version "10.0")
	(general
		(thickness 1.6)
		(legacy_teardrops no)
	)
	(paper "A4")
	(title_block
		(title "03242023_DA0F0TMBIJ0_F0T_Motherboard_J_brd_V01_OCP.brd")
		(comment 1 "Grand Teton / footprint 537 of 6105 (J111), pads 1-48 of 48")
	)
	(layers
		(0 "F.Cu" signal "TOP")
		(4 "In1.Cu" signal "GND")
		(6 "In2.Cu" signal "IN1")
		(8 "In3.Cu" signal "GND1")
		(10 "In4.Cu" signal "IN2")
		(12 "In5.Cu" signal "GND2")
		(14 "In6.Cu" signal "IN3")
		(16 "In7.Cu" signal "GND3")
		(18 "In8.Cu" signal "VCC")
		(20 "In9.Cu" signal "VCC1")
		(22 "In10.Cu" signal "GND4")
		(24 "In11.Cu" signal "IN4")
		(26 "In12.Cu" signal "GND5")
		(28 "In13.Cu" signal "IN5")
		(30 "In14.Cu" signal "GND6")
		(32 "In15.Cu" signal "IN6")
		(34 "In16.Cu" signal "GND7")
		(2 "B.Cu" signal "BOTTOM")
		(9 "F.Adhes" user "F.Adhesive")
		(11 "B.Adhes" user "B.Adhesive")
		(13 "F.Paste" user "Package Geometry/Pastemask Top")
		(15 "B.Paste" user "Package Geometry/Pastemask Bottom")
		(5 "F.SilkS" user "Ref Des/Silkscreen Top")
		(7 "B.SilkS" user "Ref Des/Silkscreen Bottom")
		(1 "F.Mask" user "Board Geometry/Soldermask Top")
		(3 "B.Mask" user "Board Geometry/Soldermask Bottom")
		(17 "Dwgs.User" user "User.Drawings")
		(19 "Cmts.User" user "User.Comments")
		(21 "Eco1.User" user "User.Eco1")
		(23 "Eco2.User" user "User.Eco2")
		(25 "Edge.Cuts" user "Board Geometry/Outline")
		(27 "Margin" user)
		(31 "F.CrtYd" user "Package Geometry/Place Bound Top")
		(29 "B.CrtYd" user "Package Geometry/Place Bound Bottom")
		(35 "F.Fab" user "Ref Des/Assembly Top")
		(33 "B.Fab" user "Ref Des/Assembly Bottom")
	)
	(footprint ""
		(layer "F.Cu")
		(at 75.65009 -440.489848)
		(property "Reference" "J111"
			(at 1.96088 23.159212 0)
			(unlocked yes)
			(layer "F.SilkS")
			(effects
				(font
					(size 0.7874 0.5842)
					(thickness 0.1524)
				)
				(justify left)
			)
		)
		(property "Value" ""
			(at 0 0 0)
			(layer "F.Fab")
			(effects
				(font
					(size 1.27 1.27)
				)
			)
		)
		(duplicate_pad_numbers_are_jumpers no)
		(pad "A1" thru_hole rect
			(at 0 0 180)
			(size 0.766318 0.766318)
			(drill 0.359918)
			(layers "*.Cu" "*.Mask")
			(remove_unused_layers no)
			(net "GPU_PEX_STRAP1")
			(clearance 0.0508)
			(thermal_gap 0.0508)
			(padstack
				(mode front_inner_back)
				(layer "Inner"
					(shape circle)
					(size 0.766318 0.766318)
					(clearance 0.0508)
				)
				(layer "B.Cu"
					(shape rect)
					(size 0.766318 0.766318)
					(clearance 0.0508)
				)
			)
		)
		(pad "A2" thru_hole circle
			(at 1.999996 0.199898 180)
			(size 0.906272 0.906272)
			(drill 0.499872)
			(layers "*.Cu" "*.Mask")
			(remove_unused_layers no)
			(net "GND")
			(clearance 0.0508)
			(thermal_gap 0.0508)
		)
		(pad "A3" thru_hole circle
			(at 3.999992 0 180)
			(size 0.766318 0.766318)
			(drill 0.359918)
			(layers "*.Cu" "*.Mask")
			(remove_unused_layers no)
			(net "GPU_BASE_ID0")
			(clearance 0.0508)
			(thermal_gap 0.0508)
		)
		(pad "A4" thru_hole circle
			(at 5.999988 0.199898 180)
			(size 0.906272 0.906272)
			(drill 0.499872)
			(layers "*.Cu" "*.Mask")
			(remove_unused_layers no)
			(net "GND")
			(clearance 0.0508)
			(thermal_gap 0.0508)
		)
		(pad "A5" thru_hole circle
			(at 7.999984 0 180)
			(size 0.766318 0.766318)
			(drill 0.359918)
			(layers "*.Cu" "*.Mask")
			(remove_unused_layers no)
			(net "GPU_PEX_STRAP0")
			(clearance 0.0508)
			(thermal_gap 0.0508)
		)
		(pad "A6" thru_hole circle
			(at 9.99998 0.199898 180)
			(size 0.906272 0.906272)
			(drill 0.499872)
			(layers "*.Cu" "*.Mask")
			(remove_unused_layers no)
			(net "GND")
			(clearance 0.0508)
			(thermal_gap 0.0508)
		)
		(pad "A7" thru_hole circle
			(at 11.999976 0 180)
			(size 0.766318 0.766318)
			(drill 0.359918)
			(layers "*.Cu" "*.Mask")
			(remove_unused_layers no)
			(net "GPU_FPGA_RST_R_BUF_N")
			(clearance 0.0508)
			(thermal_gap 0.0508)
		)
		(pad "A8" thru_hole circle
			(at 13.999972 0.199898 180)
			(size 0.906272 0.906272)
			(drill 0.499872)
			(layers "*.Cu" "*.Mask")
			(remove_unused_layers no)
			(net "GND")
			(clearance 0.0508)
			(thermal_gap 0.0508)
		)
		(pad "B1" thru_hole circle
			(at 0 1.199896 180)
			(size 0.906272 0.906272)
			(drill 0.499872)
			(layers "*.Cu" "*.Mask")
			(remove_unused_layers no)
			(net "GND")
			(clearance 0.0508)
			(thermal_gap 0.0508)
		)
		(pad "B3" thru_hole circle
			(at 3.999992 1.199896 180)
			(size 0.906272 0.906272)
			(drill 0.499872)
			(layers "*.Cu" "*.Mask")
			(remove_unused_layers no)
			(net "GND")
			(clearance 0.0508)
			(thermal_gap 0.0508)
		)
		(pad "B5" thru_hole circle
			(at 7.999984 1.199896 180)
			(size 0.906272 0.906272)
			(drill 0.499872)
			(layers "*.Cu" "*.Mask")
			(remove_unused_layers no)
			(net "GND")
			(clearance 0.0508)
			(thermal_gap 0.0508)
		)
		(pad "B7" thru_hole circle
			(at 11.999976 1.199896 180)
			(size 0.906272 0.906272)
			(drill 0.499872)
			(layers "*.Cu" "*.Mask")
			(remove_unused_layers no)
			(net "GND")
			(clearance 0.0508)
			(thermal_gap 0.0508)
		)
		(pad "D2" thru_hole circle
			(at 1.999996 3.800094 180)
			(size 0.906272 0.906272)
			(drill 0.499872)
			(layers "*.Cu" "*.Mask")
			(remove_unused_layers no)
			(net "GND")
			(clearance 0.0508)
			(thermal_gap 0.0508)
		)
		(pad "D4" thru_hole circle
			(at 5.999988 3.800094 180)
			(size 0.906272 0.906272)
			(drill 0.499872)
			(layers "*.Cu" "*.Mask")
			(remove_unused_layers no)
			(net "GND")
			(clearance 0.0508)
			(thermal_gap 0.0508)
		)
		(pad "D6" thru_hole circle
			(at 9.99998 3.800094 180)
			(size 0.906272 0.906272)
			(drill 0.499872)
			(layers "*.Cu" "*.Mask")
			(remove_unused_layers no)
			(net "GND")
			(clearance 0.0508)
			(thermal_gap 0.0508)
		)
		(pad "D8" thru_hole circle
			(at 13.999972 3.800094 180)
			(size 0.906272 0.906272)
			(drill 0.499872)
			(layers "*.Cu" "*.Mask")
			(remove_unused_layers no)
			(net "GND")
			(clearance 0.0508)
			(thermal_gap 0.0508)
		)
		(pad "E1" thru_hole circle
			(at 0 4.800092 180)
			(size 0.906272 0.906272)
			(drill 0.499872)
			(layers "*.Cu" "*.Mask")
			(remove_unused_layers no)
			(net "GND")
			(clearance 0.0508)
			(thermal_gap 0.0508)
		)
		(pad "E3" thru_hole circle
			(at 3.999992 4.800092 180)
			(size 0.906272 0.906272)
			(drill 0.499872)
			(layers "*.Cu" "*.Mask")
			(remove_unused_layers no)
			(net "GND")
			(clearance 0.0508)
			(thermal_gap 0.0508)
		)
		(pad "E5" thru_hole circle
			(at 7.999984 4.800092 180)
			(size 0.906272 0.906272)
			(drill 0.499872)
			(layers "*.Cu" "*.Mask")
			(remove_unused_layers no)
			(net "GND")
			(clearance 0.0508)
			(thermal_gap 0.0508)
		)
		(pad "E7" thru_hole circle
			(at 11.999976 4.800092 180)
			(size 0.906272 0.906272)
			(drill 0.499872)
			(layers "*.Cu" "*.Mask")
			(remove_unused_layers no)
			(net "GND")
			(clearance 0.0508)
			(thermal_gap 0.0508)
		)
		(pad "G2" thru_hole circle
			(at 1.999996 7.400036 180)
			(size 0.906272 0.906272)
			(drill 0.499872)
			(layers "*.Cu" "*.Mask")
			(remove_unused_layers no)
			(net "GND")
			(clearance 0.0508)
			(thermal_gap 0.0508)
		)
		(pad "G4" thru_hole circle
			(at 5.999988 7.400036 180)
			(size 0.906272 0.906272)
			(drill 0.499872)
			(layers "*.Cu" "*.Mask")
			(remove_unused_layers no)
			(net "GND")
			(clearance 0.0508)
			(thermal_gap 0.0508)
		)
		(pad "G6" thru_hole circle
			(at 9.99998 7.400036 180)
			(size 0.906272 0.906272)
			(drill 0.499872)
			(layers "*.Cu" "*.Mask")
			(remove_unused_layers no)
			(net "GND")
			(clearance 0.0508)
			(thermal_gap 0.0508)
		)
		(pad "G8" thru_hole circle
			(at 13.999972 7.400036 180)
			(size 0.906272 0.906272)
			(drill 0.499872)
			(layers "*.Cu" "*.Mask")
			(remove_unused_layers no)
			(net "GND")
			(clearance 0.0508)
			(thermal_gap 0.0508)
		)
		(pad "H1" thru_hole circle
			(at 0 8.400034 180)
			(size 0.906272 0.906272)
			(drill 0.499872)
			(layers "*.Cu" "*.Mask")
			(remove_unused_layers no)
			(net "GND")
			(clearance 0.0508)
			(thermal_gap 0.0508)
		)
		(pad "H3" thru_hole circle
			(at 3.999992 8.400034 180)
			(size 0.906272 0.906272)
			(drill 0.499872)
			(layers "*.Cu" "*.Mask")
			(remove_unused_layers no)
			(net "GND")
			(clearance 0.0508)
			(thermal_gap 0.0508)
		)
		(pad "H5" thru_hole circle
			(at 7.999984 8.400034 180)
			(size 0.906272 0.906272)
			(drill 0.499872)
			(layers "*.Cu" "*.Mask")
			(remove_unused_layers no)
			(net "GND")
			(clearance 0.0508)
			(thermal_gap 0.0508)
		)
		(pad "H7" thru_hole circle
			(at 11.999976 8.400034 180)
			(size 0.906272 0.906272)
			(drill 0.499872)
			(layers "*.Cu" "*.Mask")
			(remove_unused_layers no)
			(net "GND")
			(clearance 0.0508)
			(thermal_gap 0.0508)
		)
		(pad "J2" thru_hole circle
			(at 1.999996 10.999978 180)
			(size 0.906272 0.906272)
			(drill 0.499872)
			(layers "*.Cu" "*.Mask")
			(remove_unused_layers no)
			(net "GND")
			(clearance 0.0508)
			(thermal_gap 0.0508)
		)
		(pad "J4" thru_hole circle
			(at 5.999988 10.999978 180)
			(size 0.906272 0.906272)
			(drill 0.499872)
			(layers "*.Cu" "*.Mask")
			(remove_unused_layers no)
			(net "GND")
			(clearance 0.0508)
			(thermal_gap 0.0508)
		)
		(pad "J6" thru_hole circle
			(at 9.99998 10.999978 180)
			(size 0.906272 0.906272)
			(drill 0.499872)
			(layers "*.Cu" "*.Mask")
			(remove_unused_layers no)
			(net "GND")
			(clearance 0.0508)
			(thermal_gap 0.0508)
		)
		(pad "J8" thru_hole circle
			(at 13.999972 10.999978 180)
			(size 0.906272 0.906272)
			(drill 0.499872)
			(layers "*.Cu" "*.Mask")
			(remove_unused_layers no)
			(net "GND")
			(clearance 0.0508)
			(thermal_gap 0.0508)
		)
		(pad "K1" thru_hole circle
			(at 0 11.999976 180)
			(size 0.906272 0.906272)
			(drill 0.499872)
			(layers "*.Cu" "*.Mask")
			(remove_unused_layers no)
			(net "GND")
			(clearance 0.0508)
			(thermal_gap 0.0508)
		)
		(pad "K3" thru_hole circle
			(at 3.999992 11.999976 180)
			(size 0.906272 0.906272)
			(drill 0.499872)
			(layers "*.Cu" "*.Mask")
			(remove_unused_layers no)
			(net "GND")
			(clearance 0.0508)
			(thermal_gap 0.0508)
		)
		(pad "K5" thru_hole circle
			(at 7.999984 11.999976 180)
			(size 0.906272 0.906272)
			(drill 0.499872)
			(layers "*.Cu" "*.Mask")
			(remove_unused_layers no)
			(net "GND")
			(clearance 0.0508)
			(thermal_gap 0.0508)
		)
		(pad "K7" thru_hole circle
			(at 11.999976 11.999976 180)
			(size 0.906272 0.906272)
			(drill 0.499872)
			(layers "*.Cu" "*.Mask")
			(remove_unused_layers no)
			(net "GND")
			(clearance 0.0508)
			(thermal_gap 0.0508)
		)
		(pad "M2" thru_hole circle
			(at 1.999996 14.59992 180)
			(size 0.906272 0.906272)
			(drill 0.499872)
			(layers "*.Cu" "*.Mask")
			(remove_unused_layers no)
			(net "GND")
			(clearance 0.0508)
			(thermal_gap 0.0508)
		)
		(pad "M4" thru_hole circle
			(at 5.999988 14.59992 180)
			(size 0.906272 0.906272)
			(drill 0.499872)
			(layers "*.Cu" "*.Mask")
			(remove_unused_layers no)
			(net "GND")
			(clearance 0.0508)
			(thermal_gap 0.0508)
		)
		(pad "M6" thru_hole circle
			(at 9.99998 14.59992 180)
			(size 0.906272 0.906272)
			(drill 0.499872)
			(layers "*.Cu" "*.Mask")
			(remove_unused_layers no)
			(net "GND")
			(clearance 0.0508)
			(thermal_gap 0.0508)
		)
		(pad "M8" thru_hole circle
			(at 13.999972 14.59992 180)
			(size 0.906272 0.906272)
			(drill 0.499872)
			(layers "*.Cu" "*.Mask")
			(remove_unused_layers no)
			(net "GND")
			(clearance 0.0508)
			(thermal_gap 0.0508)
		)
		(pad "N1" thru_hole circle
			(at 0 15.599918 180)
			(size 0.906272 0.906272)
			(drill 0.499872)
			(layers "*.Cu" "*.Mask")
			(remove_unused_layers no)
			(net "GND")
			(clearance 0.0508)
			(thermal_gap 0.0508)
		)
		(pad "N2" thru_hole circle
			(at 1.999996 15.80007 180)
			(size 0.766318 0.766318)
			(drill 0.359918)
			(layers "*.Cu" "*.Mask")
			(remove_unused_layers no)
			(net "GPU_PRSNT_N")
			(clearance 0.0508)
			(thermal_gap 0.0508)
		)
		(pad "N3" thru_hole circle
			(at 3.999992 15.599918 180)
			(size 0.906272 0.906272)
			(drill 0.499872)
			(layers "*.Cu" "*.Mask")
			(remove_unused_layers no)
			(net "GND")
			(clearance 0.0508)
			(thermal_gap 0.0508)
		)
		(pad "N4" thru_hole circle
			(at 5.999988 15.80007 180)
			(size 0.766318 0.766318)
			(drill 0.359918)
			(layers "*.Cu" "*.Mask")
			(remove_unused_layers no)
			(net "FM_GPU_PWR_EN_R_BUF")
			(clearance 0.0508)
			(thermal_gap 0.0508)
		)
		(pad "N5" thru_hole circle
			(at 7.999984 15.599918 180)
			(size 0.906272 0.906272)
			(drill 0.499872)
			(layers "*.Cu" "*.Mask")
			(remove_unused_layers no)
			(net "GND")
			(clearance 0.0508)
			(thermal_gap 0.0508)
		)
		(pad "N6" thru_hole circle
			(at 9.99998 15.80007 180)
			(size 0.766318 0.766318)
			(drill 0.359918)
			(layers "*.Cu" "*.Mask")
			(remove_unused_layers no)
			(net "FM_GPU_PWRGD")
			(clearance 0.0508)
			(thermal_gap 0.0508)
		)
		(pad "N7" thru_hole circle
			(at 11.999976 15.599918 180)
			(size 0.906272 0.906272)
			(drill 0.499872)
			(layers "*.Cu" "*.Mask")
			(remove_unused_layers no)
			(net "GND")
			(clearance 0.0508)
			(thermal_gap 0.0508)
		)
		(pad "N8" thru_hole circle
			(at 13.999972 15.80007 180)
			(size 0.766318 0.766318)
			(drill 0.359918)
			(layers "*.Cu" "*.Mask")
			(remove_unused_layers no)
			(net "GPU_BASE_ID1")
			(clearance 0.0508)
			(thermal_gap 0.0508)
		)
	)
)
